# T6G (Grand Teton) — schematic netlist excerpt (pin names and nets, part order shuffled) for the footprints in the layout excerpt that follows; sources: Cadence DE-HDL packaged netlist, KiCad conversion of 04192023_DAF0TMB3IC0_F0TG_MB_C_brd_V02_OCP.brd

H90  HOLE  EMPTY  pkg TH  page 230 : \1\ = NC
PR3989  Q_RES  0 5% CHIP  pkg 0402LF  page 264 : A = HSC_SCREF ; B = HSC_SCREF_4
R818  Q_RES  0 5% CHIP  pkg 0402LF  page 164 : A = UART_CPU0_LVC3_UART0_R_TX ; B = UART_CPU0_LVC3_UART0_TX

(kicad_pcb
	(version 20260206)
	(generator "pcbnew")
	(generator_version "10.0")
	(general
		(thickness 1.6)
		(legacy_teardrops no)
	)
	(paper "A4")
	(title_block
		(title "04192023_DAF0TMB3IC0_F0TG_MB_C_brd_V02_OCP.brd")
		(comment 1 "Grand Teton / footprints 167-169 of 8354")
	)
	(layers
		(0 "F.Cu" signal "TOP")
		(4 "In1.Cu" signal "GND")
		(6 "In2.Cu" signal "IN1")
		(8 "In3.Cu" signal "GND1")
		(10 "In4.Cu" signal "IN2")
		(12 "In5.Cu" signal "GND2")
		(14 "In6.Cu" signal "IN3")
		(16 "In7.Cu" signal "GND3")
		(18 "In8.Cu" signal "VCC")
		(20 "In9.Cu" signal "VCC1")
		(22 "In10.Cu" signal "GND4")
		(24 "In11.Cu" signal "IN4")
		(26 "In12.Cu" signal "GND5")
		(28 "In13.Cu" signal "IN5")
		(30 "In14.Cu" signal "GND6")
		(32 "In15.Cu" signal "IN6")
		(34 "In16.Cu" signal "GND7")
		(2 "B.Cu" signal "BOTTOM")
		(9 "F.Adhes" user "F.Adhesive")
		(11 "B.Adhes" user "B.Adhesive")
		(13 "F.Paste" user "Package Geometry/Pastemask Top")
		(15 "B.Paste" user "Package Geometry/Pastemask Bottom")
		(5 "F.SilkS" user "Ref Des/Silkscreen Top")
		(7 "B.SilkS" user "Ref Des/Silkscreen Bottom")
		(1 "F.Mask" user "Board Geometry/Soldermask Top")
		(3 "B.Mask" user "Board Geometry/Soldermask Bottom")
		(17 "Dwgs.User" user "User.Drawings")
		(19 "Cmts.User" user "User.Comments")
		(21 "Eco1.User" user "User.Eco1")
		(23 "Eco2.User" user "User.Eco2")
		(25 "Edge.Cuts" user "Board Geometry/Outline")
		(27 "Margin" user)
		(31 "F.CrtYd" user "Package Geometry/Place Bound Top")
		(29 "B.CrtYd" user "Package Geometry/Place Bound Bottom")
		(35 "F.Fab" user "Ref Des/Assembly Top")
		(33 "B.Fab" user "Ref Des/Assembly Bottom")
	)
	(footprint ""
		(layer "F.Cu")
		(at 448.799966 -435.59984)
		(property "Reference" "H90"
			(at -2.943352 -3.737864 0)
			(unlocked yes)
			(layer "F.SilkS")
			(effects
				(font
					(size 0.7874 0.5842)
					(thickness 0.1524)
				)
				(justify left)
			)
		)
		(property "Value" ""
			(at 0 0 0)
			(layer "F.Fab")
			(effects
				(font
					(size 1.27 1.27)
				)
			)
		)
		(duplicate_pad_numbers_are_jumpers no)
		(fp_circle
			(center 0 0)
			(end 2.6289 0)
			(stroke
				(width 0.1524)
				(type default)
			)
			(fill no)
			(layer "F.SilkS")
		)
		(fp_circle
			(center 0 0)
			(end 2.6289 0)
			(stroke
				(width 0.1524)
				(type default)
			)
			(fill no)
			(layer "B.SilkS")
		)
		(fp_circle
			(center 0 0)
			(end 2.6289 0)
			(stroke
				(width 0.1)
				(type default)
			)
			(fill no)
			(layer "B.Fab")
		)
		(fp_circle
			(center 0 0)
			(end 2.6289 0)
			(stroke
				(width 0.1)
				(type default)
			)
			(fill no)
			(layer "F.Fab")
		)
		(pad "" np_thru_hole circle
			(at 0 0)
			(size 3.0988 3.0988)
			(drill 3.0988)
			(layers "*.Cu" "*.Mask")
			(clearance 0.254)
			(thermal_gap 0.254)
		)
		(zone
			(layers "F.Cu" "B.Cu" "In1.Cu" "In2.Cu" "In3.Cu" "In4.Cu" "In5.Cu" "In6.Cu"
				"In7.Cu" "In8.Cu" "In9.Cu" "In10.Cu" "In11.Cu" "In12.Cu" "In13.Cu" "In14.Cu"
				"In15.Cu" "In16.Cu"
			)
			(hatch none 0.5)
			(connect_pads
				(clearance 0)
			)
			(min_thickness 0.25)
			(keepout
				(tracks not_allowed)
				(vias allowed)
				(pads allowed)
				(copperpour not_allowed)
				(footprints allowed)
			)
			(placement
				(enabled no)
				(sheetname "")
			)
			(fill
				(thermal_gap 0.5)
				(thermal_bridge_width 0.5)
				(island_removal_mode 0)
			)
			(polygon
				(pts
					(arc
						(start 450.857366 -435.59984)
						(mid 446.742566 -435.59984)
						(end 450.857366 -435.59984)
					)
				)
			)
		)
	)
	(footprint ""
		(layer "F.Cu")
		(at 226.0981 -408.084782)
		(property "Reference" "PR3989"
			(at 0 0 0)
			(layer "F.SilkS")
			(hide yes)
			(effects
				(font
					(size 1.27 1.27)
				)
			)
		)
		(property "Value" ""
			(at 0 0 0)
			(layer "F.Fab")
			(effects
				(font
					(size 1.27 1.27)
				)
			)
		)
		(duplicate_pad_numbers_are_jumpers no)
		(fp_line
			(start -0.7874 -0.4064)
			(end 0.7874 -0.4064)
			(stroke
				(width 0.1524)
				(type default)
			)
			(layer "F.SilkS")
		)
		(fp_line
			(start -0.7874 0.4064)
			(end -0.7874 -0.4064)
			(stroke
				(width 0.1524)
				(type default)
			)
			(layer "F.SilkS")
		)
		(fp_line
			(start 0.7874 -0.4064)
			(end 0.7874 0.4064)
			(stroke
				(width 0.1524)
				(type default)
			)
			(layer "F.SilkS")
		)
		(fp_line
			(start 0.7874 0.4064)
			(end -0.7874 0.4064)
			(stroke
				(width 0.1524)
				(type default)
			)
			(layer "F.SilkS")
		)
		(fp_line
			(start -0.67945 -0.305054)
			(end -0.12065 -0.305054)
			(stroke
				(width 0.1)
				(type default)
			)
			(layer "F.Fab")
		)
		(fp_line
			(start -0.67945 0.3048)
			(end -0.67945 -0.305054)
			(stroke
				(width 0.1)
				(type default)
			)
			(layer "F.Fab")
		)
		(fp_line
			(start -0.12065 -0.305054)
			(end -0.12065 -0.2794)
			(stroke
				(width 0.1)
				(type default)
			)
			(layer "F.Fab")
		)
		(fp_line
			(start -0.12065 -0.2794)
			(end 0.12065 -0.2794)
			(stroke
				(width 0.1)
				(type default)
			)
			(layer "F.Fab")
		)
		(fp_line
			(start -0.12065 0.2794)
			(end -0.12065 0.3048)
			(stroke
				(width 0.1)
				(type default)
			)
			(layer "F.Fab")
		)
		(fp_line
			(start -0.12065 0.3048)
			(end -0.67945 0.3048)
			(stroke
				(width 0.1)
				(type default)
			)
			(layer "F.Fab")
		)
		(fp_line
			(start 0.120396 0.2794)
			(end -0.12065 0.2794)
			(stroke
				(width 0.1)
				(type default)
			)
			(layer "F.Fab")
		)
		(fp_line
			(start 0.120396 0.3048)
			(end 0.120396 0.2794)
			(stroke
				(width 0.1)
				(type default)
			)
			(layer "F.Fab")
		)
		(fp_line
			(start 0.12065 -0.3048)
			(end 0.67945 -0.3048)
			(stroke
				(width 0.1)
				(type default)
			)
			(layer "F.Fab")
		)
		(fp_line
			(start 0.12065 -0.2794)
			(end 0.12065 -0.3048)
			(stroke
				(width 0.1)
				(type default)
			)
			(layer "F.Fab")
		)
		(fp_line
			(start 0.67945 -0.3048)
			(end 0.67945 0.3048)
			(stroke
				(width 0.1)
				(type default)
			)
			(layer "F.Fab")
		)
		(fp_line
			(start 0.67945 0.3048)
			(end 0.120396 0.3048)
			(stroke
				(width 0.1)
				(type default)
			)
			(layer "F.Fab")
		)
		(pad "1" smd circle
			(at -0.40005 0)
			(size 0 0)
			(layers "F.Cu" "F.Mask" "F.Paste")
			(net "HSC_SCREF")
		)
		(pad "2" smd circle
			(at 0.40005 0)
			(size 0 0)
			(layers "F.Cu" "F.Mask" "F.Paste")
			(net "HSC_SCREF_4")
		)
	)
	(footprint ""
		(layer "F.Cu")
		(at 366.534446 -30.084522 -90)
		(property "Reference" "R818"
			(at 0 0 270)
			(layer "F.SilkS")
			(hide yes)
			(effects
				(font
					(size 1.27 1.27)
				)
			)
		)
		(property "Value" ""
			(at 0 0 270)
			(layer "F.Fab")
			(effects
				(font
					(size 1.27 1.27)
				)
			)
		)
		(duplicate_pad_numbers_are_jumpers no)
		(fp_line
			(start -0.7874 0.4064)
			(end -0.7874 -0.4064)
			(stroke
				(width 0.1524)
				(type default)
			)
			(layer "F.SilkS")
		)
		(fp_line
			(start 0.7874 0.4064)
			(end -0.7874 0.4064)
			(stroke
				(width 0.1524)
				(type default)
			)
			(layer "F.SilkS")
		)
		(fp_line
			(start -0.7874 -0.4064)
			(end 0.7874 -0.4064)
			(stroke
				(width 0.1524)
				(type default)
			)
			(layer "F.SilkS")
		)
		(fp_line
			(start 0.7874 -0.4064)
			(end 0.7874 0.4064)
			(stroke
				(width 0.1524)
				(type default)
			)
			(layer "F.SilkS")
		)
		(fp_line
			(start -0.67945 0.3048)
			(end -0.67945 -0.305054)
			(stroke
				(width 0.1)
				(type default)
			)
			(layer "F.Fab")
		)
		(fp_line
			(start -0.12065 0.3048)
			(end -0.67945 0.3048)
			(stroke
				(width 0.1)
				(type default)
			)
			(layer "F.Fab")
		)
		(fp_line
			(start 0.120396 0.3048)
			(end 0.120396 0.2794)
			(stroke
				(width 0.1)
				(type default)
			)
			(layer "F.Fab")
		)
		(fp_line
			(start 0.67945 0.3048)
			(end 0.120396 0.3048)
			(stroke
				(width 0.1)
				(type default)
			)
			(layer "F.Fab")
		)
		(fp_line
			(start -0.12065 0.2794)
			(end -0.12065 0.3048)
			(stroke
				(width 0.1)
				(type default)
			)
			(layer "F.Fab")
		)
		(fp_line
			(start 0.120396 0.2794)
			(end -0.12065 0.2794)
			(stroke
				(width 0.1)
				(type default)
			)
			(layer "F.Fab")
		)
		(fp_line
			(start -0.12065 -0.2794)
			(end 0.12065 -0.2794)
			(stroke
				(width 0.1)
				(type default)
			)
			(layer "F.Fab")
		)
		(fp_line
			(start 0.12065 -0.2794)
			(end 0.12065 -0.3048)
			(stroke
				(width 0.1)
				(type default)
			)
			(layer "F.Fab")
		)
		(fp_line
			(start 0.12065 -0.3048)
			(end 0.67945 -0.3048)
			(stroke
				(width 0.1)
				(type default)
			)
			(layer "F.Fab")
		)
		(fp_line
			(start 0.67945 -0.3048)
			(end 0.67945 0.3048)
			(stroke
				(width 0.1)
				(type default)
			)
			(layer "F.Fab")
		)
		(fp_line
			(start -0.67945 -0.305054)
			(end -0.12065 -0.305054)
			(stroke
				(width 0.1)
				(type default)
			)
			(layer "F.Fab")
		)
		(fp_line
			(start -0.12065 -0.305054)
			(end -0.12065 -0.2794)
			(stroke
				(width 0.1)
				(type default)
			)
			(layer "F.Fab")
		)
		(pad "1" smd circle
			(at -0.40005 0 270)
			(size 0 0)
			(layers "F.Cu" "F.Mask" "F.Paste")
			(net "UART_CPU0_LVC3_UART0_R_TX")
		)
		(pad "2" smd circle
			(at 0.40005 0 270)
			(size 0 0)
			(layers "F.Cu" "F.Mask" "F.Paste")
			(net "UART_CPU0_LVC3_UART0_TX")
		)
	)
)
